# SCM (Grand Teton) — schematic netlist excerpt (pin names and nets, part order shuffled) for the footprints in the layout excerpt that follows; sources: Cadence DE-HDL packaged netlist, KiCad conversion of 12092022_DA0F0TMDCD0_F0T_Management_Board_D_brd_V3_OCP.brd

R500  Q_RES  0 5% CHIP  pkg 0402LF  page 46 : A = SPI_TPM_CS_N_R ; B = SPI_TPM_CS_R_N
C179  Q_CAP  470PF 50V 10% X7R  pkg 0402  page 29 : A = P5V_USB_REAR ; B = GND

(kicad_pcb
	(version 20260206)
	(generator "pcbnew")
	(generator_version "10.0")
	(general
		(thickness 1.6)
		(legacy_teardrops no)
	)
	(paper "A4")
	(title_block
		(title "12092022_DA0F0TMDCD0_F0T_Management_Board_D_brd_V3_OCP.brd")
		(comment 1 "Grand Teton / footprints 301-302 of 1440")
	)
	(layers
		(0 "F.Cu" signal "TOP")
		(4 "In1.Cu" signal "GND")
		(6 "In2.Cu" signal "IN1")
		(8 "In3.Cu" signal "GND1")
		(10 "In4.Cu" signal "IN2")
		(12 "In5.Cu" signal "VCC")
		(14 "In6.Cu" signal "VCC1")
		(16 "In7.Cu" signal "IN3")
		(18 "In8.Cu" signal "GND2")
		(20 "In9.Cu" signal "IN4")
		(22 "In10.Cu" signal "GND3")
		(2 "B.Cu" signal "BOTTOM")
		(9 "F.Adhes" user "F.Adhesive")
		(11 "B.Adhes" user "B.Adhesive")
		(13 "F.Paste" user "Package Geometry/Pastemask Top")
		(15 "B.Paste" user "Package Geometry/Pastemask Bottom")
		(5 "F.SilkS" user "Ref Des/Silkscreen Top")
		(7 "B.SilkS" user "Ref Des/Silkscreen Bottom")
		(1 "F.Mask" user "Board Geometry/Soldermask Top")
		(3 "B.Mask" user "Board Geometry/Soldermask Bottom")
		(17 "Dwgs.User" user "User.Drawings")
		(19 "Cmts.User" user "User.Comments")
		(21 "Eco1.User" user "User.Eco1")
		(23 "Eco2.User" user "User.Eco2")
		(25 "Edge.Cuts" user "Board Geometry/Outline")
		(27 "Margin" user)
		(31 "F.CrtYd" user "Package Geometry/Place Bound Top")
		(29 "B.CrtYd" user "Package Geometry/Place Bound Bottom")
		(35 "F.Fab" user "Ref Des/Assembly Top")
		(33 "B.Fab" user "Ref Des/Assembly Bottom")
	)
	(footprint ""
		(layer "F.Cu")
		(at 68.189094 -97.877122)
		(property "Reference" "R500"
			(at 0 0 0)
			(layer "F.SilkS")
			(hide yes)
			(effects
				(font
					(size 1.27 1.27)
				)
			)
		)
		(property "Value" ""
			(at 0 0 0)
			(layer "F.Fab")
			(effects
				(font
					(size 1.27 1.27)
				)
			)
		)
		(duplicate_pad_numbers_are_jumpers no)
		(fp_line
			(start -0.7874 -0.4064)
			(end 0.7874 -0.4064)
			(stroke
				(width 0.1524)
				(type default)
			)
			(layer "F.SilkS")
		)
		(fp_line
			(start -0.7874 0.4064)
			(end -0.7874 -0.4064)
			(stroke
				(width 0.1524)
				(type default)
			)
			(layer "F.SilkS")
		)
		(fp_line
			(start 0.7874 -0.4064)
			(end 0.7874 0.4064)
			(stroke
				(width 0.1524)
				(type default)
			)
			(layer "F.SilkS")
		)
		(fp_line
			(start 0.7874 0.4064)
			(end -0.7874 0.4064)
			(stroke
				(width 0.1524)
				(type default)
			)
			(layer "F.SilkS")
		)
		(fp_line
			(start -0.67945 -0.305054)
			(end -0.12065 -0.305054)
			(stroke
				(width 0.1)
				(type default)
			)
			(layer "F.Fab")
		)
		(fp_line
			(start -0.67945 0.3048)
			(end -0.67945 -0.305054)
			(stroke
				(width 0.1)
				(type default)
			)
			(layer "F.Fab")
		)
		(fp_line
			(start -0.12065 -0.305054)
			(end -0.12065 -0.2794)
			(stroke
				(width 0.1)
				(type default)
			)
			(layer "F.Fab")
		)
		(fp_line
			(start -0.12065 -0.2794)
			(end 0.12065 -0.2794)
			(stroke
				(width 0.1)
				(type default)
			)
			(layer "F.Fab")
		)
		(fp_line
			(start -0.12065 0.2794)
			(end -0.12065 0.3048)
			(stroke
				(width 0.1)
				(type default)
			)
			(layer "F.Fab")
		)
		(fp_line
			(start -0.12065 0.3048)
			(end -0.67945 0.3048)
			(stroke
				(width 0.1)
				(type default)
			)
			(layer "F.Fab")
		)
		(fp_line
			(start 0.120396 0.2794)
			(end -0.12065 0.2794)
			(stroke
				(width 0.1)
				(type default)
			)
			(layer "F.Fab")
		)
		(fp_line
			(start 0.120396 0.3048)
			(end 0.120396 0.2794)
			(stroke
				(width 0.1)
				(type default)
			)
			(layer "F.Fab")
		)
		(fp_line
			(start 0.12065 -0.3048)
			(end 0.67945 -0.3048)
			(stroke
				(width 0.1)
				(type default)
			)
			(layer "F.Fab")
		)
		(fp_line
			(start 0.12065 -0.2794)
			(end 0.12065 -0.3048)
			(stroke
				(width 0.1)
				(type default)
			)
			(layer "F.Fab")
		)
		(fp_line
			(start 0.67945 -0.3048)
			(end 0.67945 0.3048)
			(stroke
				(width 0.1)
				(type default)
			)
			(layer "F.Fab")
		)
		(fp_line
			(start 0.67945 0.3048)
			(end 0.120396 0.3048)
			(stroke
				(width 0.1)
				(type default)
			)
			(layer "F.Fab")
		)
		(pad "1" smd circle
			(at -0.40005 0)
			(size 0 0)
			(layers "F.Cu" "F.Mask" "F.Paste")
			(net "SPI_TPM_CS_N_R")
		)
		(pad "2" smd circle
			(at 0.40005 0)
			(size 0 0)
			(layers "F.Cu" "F.Mask" "F.Paste")
			(net "SPI_TPM_CS_R_N")
		)
	)
	(footprint ""
		(layer "F.Cu")
		(at 47.567088 -20.435062 90)
		(property "Reference" "C179"
			(at 0 0 90)
			(layer "F.SilkS")
			(hide yes)
			(effects
				(font
					(size 1.27 1.27)
				)
			)
		)
		(property "Value" ""
			(at 0 0 90)
			(layer "F.Fab")
			(effects
				(font
					(size 1.27 1.27)
				)
			)
		)
		(duplicate_pad_numbers_are_jumpers no)
		(fp_line
			(start 0.7874 -0.4064)
			(end 0.7874 0.4064)
			(stroke
				(width 0.1524)
				(type default)
			)
			(layer "F.SilkS")
		)
		(fp_line
			(start -0.7874 -0.4064)
			(end 0.7874 -0.4064)
			(stroke
				(width 0.1524)
				(type default)
			)
			(layer "F.SilkS")
		)
		(fp_line
			(start 0.7874 0.4064)
			(end -0.7874 0.4064)
			(stroke
				(width 0.1524)
				(type default)
			)
			(layer "F.SilkS")
		)
		(fp_line
			(start -0.7874 0.4064)
			(end -0.7874 -0.4064)
			(stroke
				(width 0.1524)
				(type default)
			)
			(layer "F.SilkS")
		)
		(fp_line
			(start -0.12065 -0.305054)
			(end -0.12065 -0.2794)
			(stroke
				(width 0.1)
				(type default)
			)
			(layer "F.Fab")
		)
		(fp_line
			(start -0.67945 -0.305054)
			(end -0.12065 -0.305054)
			(stroke
				(width 0.1)
				(type default)
			)
			(layer "F.Fab")
		)
		(fp_line
			(start 0.67945 -0.3048)
			(end 0.67945 0.3048)
			(stroke
				(width 0.1)
				(type default)
			)
			(layer "F.Fab")
		)
		(fp_line
			(start 0.12065 -0.3048)
			(end 0.67945 -0.3048)
			(stroke
				(width 0.1)
				(type default)
			)
			(layer "F.Fab")
		)
		(fp_line
			(start 0.12065 -0.2794)
			(end 0.12065 -0.3048)
			(stroke
				(width 0.1)
				(type default)
			)
			(layer "F.Fab")
		)
		(fp_line
			(start -0.12065 -0.2794)
			(end 0.12065 -0.2794)
			(stroke
				(width 0.1)
				(type default)
			)
			(layer "F.Fab")
		)
		(fp_line
			(start 0.120396 0.2794)
			(end -0.12065 0.2794)
			(stroke
				(width 0.1)
				(type default)
			)
			(layer "F.Fab")
		)
		(fp_line
			(start -0.12065 0.2794)
			(end -0.12065 0.3048)
			(stroke
				(width 0.1)
				(type default)
			)
			(layer "F.Fab")
		)
		(fp_line
			(start 0.67945 0.3048)
			(end 0.120396 0.3048)
			(stroke
				(width 0.1)
				(type default)
			)
			(layer "F.Fab")
		)
		(fp_line
			(start 0.120396 0.3048)
			(end 0.120396 0.2794)
			(stroke
				(width 0.1)
				(type default)
			)
			(layer "F.Fab")
		)
		(fp_line
			(start -0.12065 0.3048)
			(end -0.67945 0.3048)
			(stroke
				(width 0.1)
				(type default)
			)
			(layer "F.Fab")
		)
		(fp_line
			(start -0.67945 0.3048)
			(end -0.67945 -0.305054)
			(stroke
				(width 0.1)
				(type default)
			)
			(layer "F.Fab")
		)
		(pad "1" smd circle
			(at -0.40005 0 90)
			(size 0 0)
			(layers "F.Cu" "F.Mask" "F.Paste")
			(net "P5V_USB_REAR")
		)
		(pad "2" smd circle
			(at 0.40005 0 90)
			(size 0 0)
			(layers "F.Cu" "F.Mask" "F.Paste")
			(net "GND")
		)
	)
)
